(kicad_pcb
	(version 20260206)
	(generator "pcbnew")
	(generator_version "10.0")
	(general
		(thickness 1.6)
		(legacy_teardrops no)
	)
	(paper "A4")
	(title_block
		(title "Bryce Canyon_F.DPB_16315-1-OCP.brd")
		(comment 1 "Bryce Canyon / footprints 1796-1798 of 2223")
	)
	(layers
		(0 "F.Cu" signal "TOP")
		(4 "In1.Cu" signal "L2GND")
		(6 "In2.Cu" signal "L3")
		(8 "In3.Cu" signal "L4GND")
		(10 "In4.Cu" signal "L5")
		(12 "In5.Cu" signal "L6VCC")
		(14 "In6.Cu" signal "L7VCC")
		(16 "In7.Cu" signal "L8")
		(18 "In8.Cu" signal "L9GND")
		(20 "In9.Cu" signal "L10")
		(22 "In10.Cu" signal "L11GND")
		(2 "B.Cu" signal "BOTTOM")
		(9 "F.Adhes" user "F.Adhesive")
		(11 "B.Adhes" user "B.Adhesive")
		(13 "F.Paste" user "Package Geometry/Pastemask Top")
		(15 "B.Paste" user "Package Geometry/Pastemask Bottom")
		(5 "F.SilkS" user "Ref Des/Silkscreen Top")
		(7 "B.SilkS" user "Ref Des/Silkscreen Bottom")
		(1 "F.Mask" user "Board Geometry/Soldermask Top")
		(3 "B.Mask" user "Board Geometry/Soldermask Bottom")
		(17 "Dwgs.User" user "User.Drawings")
		(19 "Cmts.User" user "User.Comments")
		(21 "Eco1.User" user "User.Eco1")
		(23 "Eco2.User" user "User.Eco2")
		(25 "Edge.Cuts" user "Board Geometry/Outline")
		(27 "Margin" user)
		(31 "F.CrtYd" user "Package Geometry/Place Bound Top")
		(29 "B.CrtYd" user "Package Geometry/Place Bound Bottom")
		(35 "F.Fab" user "Ref Des/Assembly Top")
		(33 "B.Fab" user "Ref Des/Assembly Bottom")
	)
	(footprint ""
		(layer "F.Cu")
		(at 325.550022 -287.910016 -90)
		(property "Reference" "HDDSAS6"
			(at 0 0 270)
			(layer "F.SilkS")
			(hide yes)
			(effects
				(font
					(size 1.27 1.27)
				)
			)
		)
		(property "Value" "SKT-SAS15P-14P-45-GP"
			(at -20.7645 -8.9789 270)
			(unlocked yes)
			(layer "F.Fab")
			(hide yes)
			(effects
				(font
					(size 1.016 1.016)
					(thickness 0.1524)
				)
			)
		)
		(property "Device Type" "10120818-001C-TRLF"
			(at -20.7645 -10.5029 270)
			(unlocked yes)
			(layer "F.Fab")
			(hide yes)
			(effects
				(font
					(size 1.016 1.016)
					(thickness 0.1524)
				)
			)
		)
		(duplicate_pad_numbers_are_jumpers no)
		(fp_line
			(start 1.651 4.2926)
			(end 1.651 3.0099)
			(stroke
				(width 0.1524)
				(type default)
			)
			(layer "F.SilkS")
		)
		(fp_line
			(start 8.509 4.2926)
			(end 1.651 4.2926)
			(stroke
				(width 0.1524)
				(type default)
			)
			(layer "F.SilkS")
		)
		(fp_line
			(start -23.4188 3.0099)
			(end -23.4188 -3.2512)
			(stroke
				(width 0.1524)
				(type default)
			)
			(layer "F.SilkS")
		)
		(fp_line
			(start 1.651 3.0099)
			(end -23.4188 3.0099)
			(stroke
				(width 0.1524)
				(type default)
			)
			(layer "F.SilkS")
		)
		(fp_line
			(start 8.509 3.0099)
			(end 8.509 4.2926)
			(stroke
				(width 0.1524)
				(type default)
			)
			(layer "F.SilkS")
		)
		(fp_line
			(start 23.4188 3.0099)
			(end 8.509 3.0099)
			(stroke
				(width 0.1524)
				(type default)
			)
			(layer "F.SilkS")
		)
		(fp_line
			(start -23.4188 -3.2512)
			(end 23.4188 -3.2512)
			(stroke
				(width 0.1524)
				(type default)
			)
			(layer "F.SilkS")
		)
		(fp_line
			(start 23.4188 -3.2512)
			(end 23.4188 3.0099)
			(stroke
				(width 0.1524)
				(type default)
			)
			(layer "F.SilkS")
		)
		(fp_line
			(start 15.5067 -3.3401)
			(end 16.2687 -3.3401)
			(stroke
				(width 0.3302)
				(type default)
			)
			(layer "F.SilkS")
		)
		(fp_poly
			(pts
				(xy 15.868904 -3.230372) (xy 16.503904 -3.865372) (xy 15.233904 -3.865372)
			)
			(stroke
				(width 0)
				(type default)
			)
			(fill yes)
			(layer "F.SilkS")
		)
		(fp_poly
			(pts
				(xy -22.8727 -2.7559) (xy 22.8727 -2.7559) (xy 22.8727 2.7559) (xy 8.255 2.7559) (xy 8.255 3.5179)
				(xy 1.905 3.5179) (xy 1.905 2.7559) (xy -22.8727 2.7559)
			)
			(stroke
				(width 0)
				(type default)
			)
			(fill no)
			(layer "F.CrtYd")
		)
		(fp_poly
			(pts
				(xy 1.397 4.5466) (xy 1.397 3.2639) (xy -23.6728 3.2639) (xy -23.6728 -3.5052) (xy 23.6728 -3.5052)
				(xy 23.6728 -0.00635) (xy 22.8727 -0.00635) (xy 22.8727 -2.7559) (xy -22.8727 -2.7559) (xy -22.8727 2.7559)
				(xy 1.905 2.7559) (xy 1.905 3.5179) (xy 8.255 3.5179) (xy 8.255 2.7559) (xy 22.8727 2.7559) (xy 22.8727 0.00635)
				(xy 23.6728 0.00635) (xy 23.6728 3.2639) (xy 8.763 3.2639) (xy 8.763 4.5466)
			)
			(stroke
				(width 0)
				(type default)
			)
			(fill no)
			(layer "F.CrtYd")
		)
		(fp_poly
			(pts
				(xy 1.397 4.5466) (xy 1.397 3.2639) (xy -23.6728 3.2639) (xy -23.6728 -3.5052) (xy 23.6728 -3.5052)
				(xy 23.6728 3.2639) (xy 8.763 3.2639) (xy 8.763 4.5466)
			)
			(stroke
				(width 0)
				(type default)
			)
			(fill no)
			(layer "F.Fab")
		)
		(pad "" np_thru_hole circle
			(at -18.874994 0 270)
			(size 0.254 0.254)
			(drill 1.3462)
			(layers "*.Cu" "*.Mask")
			(clearance 0.9017)
			(thermal_gap 0.9017)
		)
		(pad "" np_thru_hole circle
			(at 18.874994 0 270)
			(size 0.254 0.254)
			(drill 0.9398)
			(layers "*.Cu" "*.Mask")
			(clearance 0.6985)
			(thermal_gap 0.6985)
		)
		(pad "G1" smd rect
			(at 21.874988 0 270)
			(size 2.5908 2.5908)
			(layers "F.Cu" "F.Mask" "F.Paste")
			(net "GND")
		)
		(pad "G2" smd rect
			(at -21.874988 0 270)
			(size 2.5908 2.5908)
			(layers "F.Cu" "F.Mask" "F.Paste")
			(net "GND")
		)
		(pad "P1" smd rect
			(at 1.905 -1.82499 270)
			(size 0.6096 2.3622)
			(layers "F.Cu" "F.Mask" "F.Paste")
			(net "Net_2011")
		)
		(pad "P2" smd rect
			(at 0.635 -1.82499 270)
			(size 0.6096 2.3622)
			(layers "F.Cu" "F.Mask" "F.Paste")
			(net "Net_2012")
		)
		(pad "P3" smd rect
			(at -0.635 -1.82499 270)
			(size 0.6096 2.3622)
			(layers "F.Cu" "F.Mask" "F.Paste")
			(net "Net_2013")
		)
		(pad "P4" smd rect
			(at -1.905 -1.82499 270)
			(size 0.6096 2.3622)
			(layers "F.Cu" "F.Mask" "F.Paste")
			(net "GND")
		)
		(pad "P5" smd rect
			(at -3.175 -1.82499 270)
			(size 0.6096 2.3622)
			(layers "F.Cu" "F.Mask" "F.Paste")
			(net "HDD_PRSNT_6")
		)
		(pad "P6" smd rect
			(at -4.445 -1.82499 270)
			(size 0.6096 2.3622)
			(layers "F.Cu" "F.Mask" "F.Paste")
			(net "GND")
		)
		(pad "P7" smd rect
			(at -5.715 -1.82499 270)
			(size 0.6096 2.3622)
			(layers "F.Cu" "F.Mask" "F.Paste")
			(net "5V_PRE_6")
		)
		(pad "P8" smd rect
			(at -6.985 -1.82499 270)
			(size 0.6096 2.3622)
			(layers "F.Cu" "F.Mask" "F.Paste")
			(net "P5V_HDD6")
		)
		(pad "P9" smd rect
			(at -8.255 -1.82499 270)
			(size 0.6096 2.3622)
			(layers "F.Cu" "F.Mask" "F.Paste")
			(net "P5V_HDD6")
		)
		(pad "P10" smd rect
			(at -9.525 -1.82499 270)
			(size 0.6096 2.3622)
			(layers "F.Cu" "F.Mask" "F.Paste")
			(net "GND")
		)
		(pad "P11" smd rect
			(at -10.795 -1.82499 270)
			(size 0.6096 2.3622)
			(layers "F.Cu" "F.Mask" "F.Paste")
			(net "ACT_HDD_6")
		)
		(pad "P12" smd rect
			(at -12.065 -1.82499 270)
			(size 0.6096 2.3622)
			(layers "F.Cu" "F.Mask" "F.Paste")
			(net "GND")
		)
		(pad "P13" smd rect
			(at -13.335 -1.82499 270)
			(size 0.6096 2.3622)
			(layers "F.Cu" "F.Mask" "F.Paste")
			(net "12V_PRE_6")
		)
		(pad "P14" smd rect
			(at -14.605 -1.82499 270)
			(size 0.6096 2.3622)
			(layers "F.Cu" "F.Mask" "F.Paste")
			(net "P12V_HDD6")
		)
		(pad "P15" smd rect
			(at -15.875 -1.82499 270)
			(size 0.6096 2.3622)
			(layers "F.Cu" "F.Mask" "F.Paste")
			(net "P12V_HDD6")
		)
		(pad "S1" smd rect
			(at 15.875 -1.82499 270)
			(size 0.6096 2.3622)
			(layers "F.Cu" "F.Mask" "F.Paste")
			(net "GND")
		)
		(pad "S2" smd rect
			(at 14.605 -1.82499 270)
			(size 0.6096 2.3622)
			(layers "F.Cu" "F.Mask" "F.Paste")
			(net "SAS_HDD_RX_P6")
		)
		(pad "S3" smd rect
			(at 13.335 -1.82499 270)
			(size 0.6096 2.3622)
			(layers "F.Cu" "F.Mask" "F.Paste")
			(net "SAS_HDD_RX_N6")
		)
		(pad "S4" smd rect
			(at 12.065 -1.82499 270)
			(size 0.6096 2.3622)
			(layers "F.Cu" "F.Mask" "F.Paste")
			(net "GND")
		)
		(pad "S5" smd rect
			(at 10.795 -1.82499 270)
			(size 0.6096 2.3622)
			(layers "F.Cu" "F.Mask" "F.Paste")
			(net "PHY_DRV_A_TO_SCC_A_6_DN")
		)
		(pad "S6" smd rect
			(at 9.525 -1.82499 270)
			(size 0.6096 2.3622)
			(layers "F.Cu" "F.Mask" "F.Paste")
			(net "PHY_DRV_A_TO_SCC_A_6_DP")
		)
		(pad "S7" smd rect
			(at 8.255 -1.82499 270)
			(size 0.6096 2.3622)
			(layers "F.Cu" "F.Mask" "F.Paste")
			(net "GND")
		)
		(pad "S8" smd rect
			(at 7.480046 2.845054 270)
			(size 0.508 2.3622)
			(layers "F.Cu" "F.Mask" "F.Paste")
			(net "GND")
		)
		(pad "S9" smd rect
			(at 6.679946 2.845054 270)
			(size 0.508 2.3622)
			(layers "F.Cu" "F.Mask" "F.Paste")
			(net "Net_478")
		)
		(pad "S10" smd rect
			(at 5.8801 2.845054 270)
			(size 0.508 2.3622)
			(layers "F.Cu" "F.Mask" "F.Paste")
			(net "Net_370")
		)
		(pad "S11" smd rect
			(at 5.08 2.845054 270)
			(size 0.508 2.3622)
			(layers "F.Cu" "F.Mask" "F.Paste")
			(net "GND")
		)
		(pad "S12" smd rect
			(at 4.2799 2.845054 270)
			(size 0.508 2.3622)
			(layers "F.Cu" "F.Mask" "F.Paste")
			(net "Net_406")
		)
		(pad "S13" smd rect
			(at 3.480054 2.845054 270)
			(size 0.508 2.3622)
			(layers "F.Cu" "F.Mask" "F.Paste")
			(net "Net_442")
		)
		(pad "S14" smd rect
			(at 2.679954 2.845054 270)
			(size 0.508 2.3622)
			(layers "F.Cu" "F.Mask" "F.Paste")
			(net "GND")
		)
		(zone
			(layer "F.Cu")
			(hatch none 0.5)
			(connect_pads
				(clearance 0)
			)
			(min_thickness 0.25)
			(keepout
				(tracks allowed)
				(vias not_allowed)
				(pads allowed)
				(copperpour not_allowed)
				(footprints allowed)
			)
			(placement
				(enabled no)
				(sheetname "")
			)
			(fill
				(thermal_gap 0.5)
				(thermal_bridge_width 0.5)
				(island_removal_mode 0)
			)
			(polygon
				(pts
					(xy 329.207622 -304.648616) (xy 322.133722 -304.648616) (xy 322.133722 -311.582816) (xy 323.238622 -311.582816)
					(xy 323.238622 -307.468016) (xy 327.861422 -307.468016) (xy 327.861422 -311.582816) (xy 329.207622 -311.582816)
				)
			)
		)
		(zone
			(layer "F.Cu")
			(hatch none 0.5)
			(connect_pads
				(clearance 0)
			)
			(min_thickness 0.25)
			(keepout
				(tracks not_allowed)
				(vias allowed)
				(pads allowed)
				(copperpour not_allowed)
				(footprints allowed)
			)
			(placement
				(enabled no)
				(sheetname "")
			)
			(fill
				(thermal_gap 0.5)
				(thermal_bridge_width 0.5)
				(island_removal_mode 0)
			)
			(polygon
				(pts
					(xy 329.207622 -304.648616) (xy 322.133722 -304.648616) (xy 322.133722 -311.582816) (xy 323.238622 -311.582816)
					(xy 323.238622 -307.468016) (xy 327.861422 -307.468016) (xy 327.861422 -311.582816) (xy 329.207622 -311.582816)
				)
			)
		)
		(zone
			(layer "F.Cu")
			(hatch none 0.5)
			(connect_pads
				(clearance 0)
			)
			(min_thickness 0.25)
			(keepout
				(tracks allowed)
				(vias not_allowed)
				(pads allowed)
				(copperpour not_allowed)
				(footprints allowed)
			)
			(placement
				(enabled no)
				(sheetname "")
			)
			(fill
				(thermal_gap 0.5)
				(thermal_bridge_width 0.5)
				(island_removal_mode 0)
			)
			(polygon
				(pts
					(xy 329.207622 -271.171416) (xy 322.133722 -271.171416) (xy 322.133722 -264.237216) (xy 323.238622 -264.237216)
					(xy 323.238622 -268.352016) (xy 327.861422 -268.352016) (xy 327.861422 -264.237216) (xy 329.207622 -264.237216)
				)
			)
		)
		(zone
			(layer "F.Cu")
			(hatch none 0.5)
			(connect_pads
				(clearance 0)
			)
			(min_thickness 0.25)
			(keepout
				(tracks not_allowed)
				(vias allowed)
				(pads allowed)
				(copperpour not_allowed)
				(footprints allowed)
			)
			(placement
				(enabled no)
				(sheetname "")
			)
			(fill
				(thermal_gap 0.5)
				(thermal_bridge_width 0.5)
				(island_removal_mode 0)
			)
			(polygon
				(pts
					(xy 329.207622 -271.171416) (xy 322.133722 -271.171416) (xy 322.133722 -264.237216) (xy 323.238622 -264.237216)
					(xy 323.238622 -268.352016) (xy 327.861422 -268.352016) (xy 327.861422 -264.237216) (xy 329.207622 -264.237216)
				)
			)
		)
		(zone
			(layers "F.Cu" "B.Cu" "In1.Cu" "In2.Cu" "In3.Cu" "In4.Cu" "In5.Cu" "In6.Cu"
				"In7.Cu" "In8.Cu" "In9.Cu" "In10.Cu"
			)
			(hatch none 0.5)
			(connect_pads
				(clearance 0)
			)
			(min_thickness 0.25)
			(keepout
				(tracks not_allowed)
				(vias allowed)
				(pads allowed)
				(copperpour not_allowed)
				(footprints allowed)
			)
			(placement
				(enabled no)
				(sheetname "")
			)
			(fill
				(thermal_gap 0.5)
				(thermal_bridge_width 0.5)
				(island_removal_mode 0)
			)
			(polygon
				(pts
					(arc
						(start 326.324722 -269.035022)
						(mid 324.775322 -269.035022)
						(end 326.324722 -269.035022)
					)
				)
			)
		)
		(zone
			(layers "F.Cu" "B.Cu" "In1.Cu" "In2.Cu" "In3.Cu" "In4.Cu" "In5.Cu" "In6.Cu"
				"In7.Cu" "In8.Cu" "In9.Cu" "In10.Cu"
			)
			(hatch none 0.5)
			(connect_pads
				(clearance 0)
			)
			(min_thickness 0.25)
			(keepout
				(tracks not_allowed)
				(vias allowed)
				(pads allowed)
				(copperpour not_allowed)
				(footprints allowed)
			)
			(placement
				(enabled no)
				(sheetname "")
			)
			(fill
				(thermal_gap 0.5)
				(thermal_bridge_width 0.5)
				(island_removal_mode 0)
			)
			(polygon
				(pts
					(arc
						(start 326.527922 -306.78501)
						(mid 324.572122 -306.78501)
						(end 326.527922 -306.78501)
					)
				)
			)
		)
	)
	(footprint ""
		(layer "F.Cu")
		(at 482.489002 -162.749992 -90)
		(property "Reference" "VIA23"
			(at 0 0 270)
			(layer "F.SilkS")
			(hide yes)
			(effects
				(font
					(size 1.27 1.27)
				)
			)
		)
		(property "Value" "100OHM-8L-1D6MM-L18L16-GP"
			(at -3.7211 -4.5085 270)
			(unlocked yes)
			(layer "F.Fab")
			(hide yes)
			(effects
				(font
					(size 1.016 1.016)
					(thickness 0.1524)
				)
			)
		)
		(property "Device Type" "VIA-PCIE-4P-394076"
			(at -3.7211 -6.0325 270)
			(unlocked yes)
			(layer "F.Fab")
			(hide yes)
			(effects
				(font
					(size 1.016 1.016)
					(thickness 0.1524)
				)
			)
		)
		(duplicate_pad_numbers_are_jumpers no)
		(fp_rect
			(start -1.9685 0.381)
			(end 1.9685 -0.381)
			(stroke
				(width 0)
				(type default)
			)
			(fill no)
			(layer "F.CrtYd")
		)
		(fp_rect
			(start -1.9685 0.381)
			(end 1.9685 -0.381)
			(stroke
				(width 0)
				(type default)
			)
			(fill no)
			(layer "F.Fab")
		)
		(pad "1" thru_hole circle
			(at -1.5875 0 270)
			(size 0.508 0.508)
			(drill 0.254)
			(layers "*.Cu" "*.Mask")
			(remove_unused_layers no)
			(net "GND")
			(clearance 0.127)
			(thermal_gap 0.127)
		)
		(pad "2" thru_hole circle
			(at -0.5715 0 270)
			(size 0.508 0.508)
			(drill 0.254)
			(layers "*.Cu" "*.Mask")
			(remove_unused_layers no)
			(net "PHY_DRV_A_TO_SCC_A_23_DP")
			(clearance 0.127)
			(thermal_gap 0.127)
		)
		(pad "3" thru_hole circle
			(at 0.5715 0 270)
			(size 0.508 0.508)
			(drill 0.254)
			(layers "*.Cu" "*.Mask")
			(remove_unused_layers no)
			(net "PHY_DRV_A_TO_SCC_A_23_DN")
			(clearance 0.127)
			(thermal_gap 0.127)
		)
		(pad "4" thru_hole circle
			(at 1.5875 0 270)
			(size 0.508 0.508)
			(drill 0.254)
			(layers "*.Cu" "*.Mask")
			(remove_unused_layers no)
			(net "GND")
			(clearance 0.127)
			(thermal_gap 0.127)
		)
	)
	(footprint ""
		(layer "F.Cu")
		(at 362.310426 -131.891278)
		(property "Reference" "C566"
			(at 0 0 0)
			(layer "F.SilkS")
			(hide yes)
			(effects
				(font
					(size 1.27 1.27)
				)
			)
		)
		(property "Value" "SC1U16V3KX-5GP"
			(at 0 -2.8194 0)
			(unlocked yes)
			(layer "F.Fab")
			(hide yes)
			(effects
				(font
					(size 1.016 1.016)
					(thickness 0.1524)
				)
			)
		)
		(property "Device Type" "C603H36"
			(at 0 -4.3434 0)
			(unlocked yes)
			(layer "F.Fab")
			(hide yes)
			(effects
				(font
					(size 1.016 1.016)
					(thickness 0.1524)
				)
			)
		)
		(duplicate_pad_numbers_are_jumpers no)
		(fp_line
			(start 0.508 0)
			(end -0.508 0)
			(stroke
				(width 0.2032)
				(type default)
			)
			(layer "F.SilkS")
		)
		(fp_rect
			(start -0.5842 1.3335)
			(end 0.5842 -1.3335)
			(stroke
				(width 0)
				(type default)
			)
			(fill no)
			(layer "F.CrtYd")
		)
		(fp_rect
			(start -0.5842 1.3335)
			(end 0.5842 -1.3335)
			(stroke
				(width 0)
				(type default)
			)
			(fill no)
			(layer "F.Fab")
		)
		(pad "1" smd custom
			(at 0 -0.762)
			(size 0.2159 0.2159)
			(layers "F.Cu" "F.Mask" "F.Paste")
			(net "MB1_CM_OV_R")
			(options
				(clearance outline)
				(anchor circle)
			)
			(primitives
				(gr_poly
					(pts
						(arc
							(start -0.3302 -0.4318)
							(mid -0.402042 -0.402042)
							(end -0.4318 -0.3302)
						)
						(arc
							(start -0.4318 0.3302)
							(mid -0.402042 0.402042)
							(end -0.3302 0.4318)
						)
						(arc
							(start 0.3302 0.4318)
							(mid 0.402042 0.402042)
							(end 0.4318 0.3302)
						)
						(arc
							(start 0.4318 -0.3302)
							(mid 0.402042 -0.402042)
							(end 0.3302 -0.4318)
						)
					)
					(width 0)
					(fill yes)
				)
			)
		)
		(pad "2" smd custom
			(at 0 0.762)
			(size 0.2159 0.2159)
			(layers "F.Cu" "F.Mask" "F.Paste")
			(net "AGND_CURRENT_MONOB")
			(options
				(clearance outline)
				(anchor circle)
			)
			(primitives
				(gr_poly
					(pts
						(arc
							(start -0.3302 -0.4318)
							(mid -0.402042 -0.402042)
							(end -0.4318 -0.3302)
						)
						(arc
							(start -0.4318 0.3302)
							(mid -0.402042 0.402042)
							(end -0.3302 0.4318)
						)
						(arc
							(start 0.3302 0.4318)
							(mid 0.402042 0.402042)
							(end 0.4318 0.3302)
						)
						(arc
							(start 0.4318 -0.3302)
							(mid 0.402042 -0.402042)
							(end 0.3302 -0.4318)
						)
					)
					(width 0)
					(fill yes)
				)
			)
		)
	)
)
